(kicad_pcb
	(version 20260206)
	(generator "pcbnew")
	(generator_version "10.0")
	(general
		(thickness 1.6)
		(legacy_teardrops no)
	)
	(paper "A4")
	(title_block
		(title "Wiwynn_Tioga_Pass_MB.brd")
		(comment 1 "Tioga Pass / footprints 556-562 of 4770")
	)
	(layers
		(0 "F.Cu" signal "TOP")
		(4 "In1.Cu" signal "L2GND")
		(6 "In2.Cu" signal "L3")
		(8 "In3.Cu" signal "L4GND")
		(10 "In4.Cu" signal "L5")
		(12 "In5.Cu" signal "L6GND")
		(14 "In6.Cu" signal "L7VCC")
		(16 "In7.Cu" signal "L8VCC")
		(18 "In8.Cu" signal "L9GND")
		(20 "In9.Cu" signal "L10")
		(22 "In10.Cu" signal "L11GND")
		(24 "In11.Cu" signal "L12")
		(26 "In12.Cu" signal "L13GND")
		(2 "B.Cu" signal "BOTTOM")
		(9 "F.Adhes" user "F.Adhesive")
		(11 "B.Adhes" user "B.Adhesive")
		(13 "F.Paste" user "Package Geometry/Pastemask Top")
		(15 "B.Paste" user "Package Geometry/Pastemask Bottom")
		(5 "F.SilkS" user "Ref Des/Silkscreen Top")
		(7 "B.SilkS" user "Ref Des/Silkscreen Bottom")
		(1 "F.Mask" user "Board Geometry/Soldermask Top")
		(3 "B.Mask" user "Board Geometry/Soldermask Bottom")
		(17 "Dwgs.User" user "User.Drawings")
		(19 "Cmts.User" user "User.Comments")
		(21 "Eco1.User" user "User.Eco1")
		(23 "Eco2.User" user "User.Eco2")
		(25 "Edge.Cuts" user "Board Geometry/Outline")
		(27 "Margin" user)
		(31 "F.CrtYd" user "Package Geometry/Place Bound Top")
		(29 "B.CrtYd" user "Package Geometry/Place Bound Bottom")
		(35 "F.Fab" user "Ref Des/Assembly Top")
		(33 "B.Fab" user "Ref Des/Assembly Bottom")
	)
	(footprint ""
		(layer "F.Cu")
		(at 455.217784 -1.539494 90)
		(property "Reference" "RN8F1"
			(at -0.8382 -0.67818 90)
			(unlocked yes)
			(layer "F.SilkS")
			(effects
				(font
					(size 0.4064 0.254)
					(thickness 0.1524)
				)
				(justify left)
			)
		)
		(property "Value" ""
			(at 0 0 90)
			(layer "F.Fab")
			(effects
				(font
					(size 1.27 1.27)
				)
			)
		)
		(duplicate_pad_numbers_are_jumpers no)
		(fp_poly
			(pts
				(xy -0.2794 -0.1016) (xy 0.2794 -0.1016) (xy 0.2794 0.9906) (xy -0.2794 0.9906)
			)
			(stroke
				(width 0)
				(type default)
			)
			(fill no)
			(layer "F.CrtYd")
		)
		(fp_line
			(start 0.2794 -0.1016)
			(end -0.2794 -0.1016)
			(stroke
				(width 0.1)
				(type default)
			)
			(layer "F.Fab")
		)
		(fp_line
			(start -0.2794 -0.1016)
			(end -0.2794 0.9906)
			(stroke
				(width 0.1)
				(type default)
			)
			(layer "F.Fab")
		)
		(fp_line
			(start 0.2794 0.9906)
			(end 0.2794 -0.1016)
			(stroke
				(width 0.1)
				(type default)
			)
			(layer "F.Fab")
		)
		(fp_line
			(start -0.2794 0.9906)
			(end 0.2794 0.9906)
			(stroke
				(width 0.1)
				(type default)
			)
			(layer "F.Fab")
		)
		(pad "1" smd rect
			(at 0 0 90)
			(size 0.508 0.508)
			(layers "F.Cu" "F.Mask" "F.Paste")
			(net "P3V3_STBY")
		)
		(pad "2" smd rect
			(at 0 0.889 90)
			(size 0.508 0.508)
			(layers "F.Cu" "F.Mask" "F.Paste")
			(net "PU_SPI_BMC_BT_CS0_N")
		)
		(zone
			(layer "F.Cu")
			(hatch none 0.5)
			(connect_pads
				(clearance 0)
			)
			(min_thickness 0.25)
			(keepout
				(tracks allowed)
				(vias not_allowed)
				(pads allowed)
				(copperpour not_allowed)
				(footprints allowed)
			)
			(placement
				(enabled no)
				(sheetname "")
			)
			(fill
				(thermal_gap 0.5)
				(thermal_bridge_width 0.5)
				(island_removal_mode 0)
			)
			(polygon
				(pts
					(xy 455.471784 -1.285494) (xy 455.471784 -1.793494) (xy 455.852784 -1.793494) (xy 455.852784 -1.285494)
				)
			)
		)
		(zone
			(layer "F.Cu")
			(hatch none 0.5)
			(connect_pads
				(clearance 0)
			)
			(min_thickness 0.25)
			(keepout
				(tracks not_allowed)
				(vias allowed)
				(pads allowed)
				(copperpour not_allowed)
				(footprints allowed)
			)
			(placement
				(enabled no)
				(sheetname "")
			)
			(fill
				(thermal_gap 0.5)
				(thermal_bridge_width 0.5)
				(island_removal_mode 0)
			)
			(polygon
				(pts
					(xy 455.852784 -1.285494) (xy 455.852784 -1.793494) (xy 455.471784 -1.793494) (xy 455.471784 -1.285494)
				)
			)
		)
	)
	(footprint ""
		(layer "F.Cu")
		(at 263.1948 -79.6036 180)
		(property "Reference" "C5D15"
			(at 0 0 180)
			(layer "F.SilkS")
			(hide yes)
			(effects
				(font
					(size 1.27 1.27)
				)
			)
		)
		(property "Value" ""
			(at 0 0 180)
			(layer "F.Fab")
			(effects
				(font
					(size 1.27 1.27)
				)
			)
		)
		(duplicate_pad_numbers_are_jumpers no)
		(fp_poly
			(pts
				(xy -0.4953 -0.2032) (xy 0.4953 -0.2032) (xy 0.4953 1.6002) (xy -0.4953 1.6002)
			)
			(stroke
				(width 0)
				(type default)
			)
			(fill no)
			(layer "F.CrtYd")
		)
		(fp_line
			(start 0.4953 1.6002)
			(end -0.4953 1.6002)
			(stroke
				(width 0.1)
				(type default)
			)
			(layer "F.Fab")
		)
		(fp_line
			(start 0.4953 -0.2032)
			(end 0.4953 1.6002)
			(stroke
				(width 0.1)
				(type default)
			)
			(layer "F.Fab")
		)
		(fp_line
			(start -0.4953 1.6002)
			(end -0.4953 -0.2032)
			(stroke
				(width 0.1)
				(type default)
			)
			(layer "F.Fab")
		)
		(fp_line
			(start -0.4953 -0.2032)
			(end 0.4953 -0.2032)
			(stroke
				(width 0.1)
				(type default)
			)
			(layer "F.Fab")
		)
		(pad "1" smd rect
			(at 0 0 180)
			(size 0.762 0.889)
			(layers "F.Cu" "F.Mask" "F.Paste")
			(net "PVCCIN_CPU0")
		)
		(pad "2" smd rect
			(at 0 1.397 180)
			(size 0.762 0.889)
			(layers "F.Cu" "F.Mask" "F.Paste")
			(net "GND")
		)
		(zone
			(layer "F.Cu")
			(hatch none 0.5)
			(connect_pads
				(clearance 0)
			)
			(min_thickness 0.25)
			(keepout
				(tracks not_allowed)
				(vias allowed)
				(pads allowed)
				(copperpour not_allowed)
				(footprints allowed)
			)
			(placement
				(enabled no)
				(sheetname "")
			)
			(fill
				(thermal_gap 0.5)
				(thermal_bridge_width 0.5)
				(island_removal_mode 0)
			)
			(polygon
				(pts
					(xy 263.5758 -80.0481) (xy 262.8138 -80.0481) (xy 262.8138 -80.5561) (xy 263.5758 -80.5561)
				)
			)
		)
	)
	(footprint ""
		(layer "F.Cu")
		(at 390.906 -151.236426)
		(property "Reference" "C8A7"
			(at 0 0 0)
			(layer "F.SilkS")
			(hide yes)
			(effects
				(font
					(size 1.27 1.27)
				)
			)
		)
		(property "Value" ""
			(at 0 0 0)
			(layer "F.Fab")
			(effects
				(font
					(size 1.27 1.27)
				)
			)
		)
		(duplicate_pad_numbers_are_jumpers no)
		(fp_poly
			(pts
				(xy 0.3048 -0.1016) (xy 0.3048 0.9906) (xy -0.3048 0.9906) (xy -0.3048 -0.1016)
			)
			(stroke
				(width 0)
				(type default)
			)
			(fill no)
			(layer "F.CrtYd")
		)
		(fp_line
			(start -0.3048 -0.1016)
			(end -0.3048 0.9906)
			(stroke
				(width 0.1)
				(type default)
			)
			(layer "F.Fab")
		)
		(fp_line
			(start -0.3048 0.9906)
			(end 0.3048 0.9906)
			(stroke
				(width 0.1)
				(type default)
			)
			(layer "F.Fab")
		)
		(fp_line
			(start 0.3048 -0.1016)
			(end -0.3048 -0.1016)
			(stroke
				(width 0.1)
				(type default)
			)
			(layer "F.Fab")
		)
		(fp_line
			(start 0.3048 0.9906)
			(end 0.3048 -0.1016)
			(stroke
				(width 0.1)
				(type default)
			)
			(layer "F.Fab")
		)
		(pad "1" smd rect
			(at 0 0)
			(size 0.508 0.508)
			(layers "F.Cu" "F.Mask" "F.Paste")
			(net "VR_PVNN_P1V05_PCH_VD12")
		)
		(pad "2" smd rect
			(at 0 0.889)
			(size 0.508 0.508)
			(layers "F.Cu" "F.Mask" "F.Paste")
			(net "GND")
		)
		(zone
			(layer "F.Cu")
			(hatch none 0.5)
			(connect_pads
				(clearance 0)
			)
			(min_thickness 0.25)
			(keepout
				(tracks allowed)
				(vias not_allowed)
				(pads allowed)
				(copperpour not_allowed)
				(footprints allowed)
			)
			(placement
				(enabled no)
				(sheetname "")
			)
			(fill
				(thermal_gap 0.5)
				(thermal_bridge_width 0.5)
				(island_removal_mode 0)
			)
			(polygon
				(pts
					(xy 390.652 -150.982426) (xy 391.16 -150.982426) (xy 391.16 -150.601426) (xy 390.652 -150.601426)
				)
			)
		)
		(zone
			(layer "F.Cu")
			(hatch none 0.5)
			(connect_pads
				(clearance 0)
			)
			(min_thickness 0.25)
			(keepout
				(tracks not_allowed)
				(vias allowed)
				(pads allowed)
				(copperpour not_allowed)
				(footprints allowed)
			)
			(placement
				(enabled no)
				(sheetname "")
			)
			(fill
				(thermal_gap 0.5)
				(thermal_bridge_width 0.5)
				(island_removal_mode 0)
			)
			(polygon
				(pts
					(xy 390.652 -150.601426) (xy 391.16 -150.601426) (xy 391.16 -150.982426) (xy 390.652 -150.982426)
				)
			)
		)
	)
	(footprint ""
		(layer "F.Cu")
		(at -1.41986 -131.65836 180)
		(property "Reference" "R1B5"
			(at 0 0 180)
			(layer "F.SilkS")
			(hide yes)
			(effects
				(font
					(size 1.27 1.27)
				)
			)
		)
		(property "Value" ""
			(at 0 0 180)
			(layer "F.Fab")
			(effects
				(font
					(size 1.27 1.27)
				)
			)
		)
		(duplicate_pad_numbers_are_jumpers no)
		(fp_rect
			(start 0.2794 -0.1016)
			(end -0.2794 0.9906)
			(stroke
				(width 0)
				(type default)
			)
			(fill no)
			(layer "F.CrtYd")
		)
		(fp_line
			(start 0.2794 0.9906)
			(end 0.2794 -0.1016)
			(stroke
				(width 0.1)
				(type default)
			)
			(layer "F.Fab")
		)
		(fp_line
			(start 0.2794 -0.1016)
			(end -0.2794 -0.1016)
			(stroke
				(width 0.1)
				(type default)
			)
			(layer "F.Fab")
		)
		(fp_line
			(start -0.2794 0.9906)
			(end 0.2794 0.9906)
			(stroke
				(width 0.1)
				(type default)
			)
			(layer "F.Fab")
		)
		(fp_line
			(start -0.2794 -0.1016)
			(end -0.2794 0.9906)
			(stroke
				(width 0.1)
				(type default)
			)
			(layer "F.Fab")
		)
		(pad "1" smd rect
			(at 0 0 180)
			(size 0.508 0.508)
			(layers "F.Cu" "F.Mask" "F.Paste")
			(net "PWRGD_PVDDQ_KLM_R")
		)
		(pad "2" smd rect
			(at 0 0.889 180)
			(size 0.508 0.508)
			(layers "F.Cu" "F.Mask" "F.Paste")
			(net "PWRGD_PVDDQ_KLM")
		)
		(zone
			(layer "F.Cu")
			(hatch none 0.5)
			(connect_pads
				(clearance 0)
			)
			(min_thickness 0.25)
			(keepout
				(tracks not_allowed)
				(vias allowed)
				(pads allowed)
				(copperpour not_allowed)
				(footprints allowed)
			)
			(placement
				(enabled no)
				(sheetname "")
			)
			(fill
				(thermal_gap 0.5)
				(thermal_bridge_width 0.5)
				(island_removal_mode 0)
			)
			(polygon
				(pts
					(xy -1.67386 -131.91236) (xy -1.16586 -131.91236) (xy -1.16586 -132.29336) (xy -1.67386 -132.29336)
				)
			)
		)
		(zone
			(layer "F.Cu")
			(hatch none 0.5)
			(connect_pads
				(clearance 0)
			)
			(min_thickness 0.25)
			(keepout
				(tracks allowed)
				(vias not_allowed)
				(pads allowed)
				(copperpour not_allowed)
				(footprints allowed)
			)
			(placement
				(enabled no)
				(sheetname "")
			)
			(fill
				(thermal_gap 0.5)
				(thermal_bridge_width 0.5)
				(island_removal_mode 0)
			)
			(polygon
				(pts
					(xy -1.67386 -131.91236) (xy -1.16586 -131.91236) (xy -1.16586 -132.29336) (xy -1.67386 -132.29336)
				)
			)
		)
	)
	(footprint ""
		(layer "F.Cu")
		(at 30.013656 -78.33741)
		(property "Reference" "CT21"
			(at -0.88773 0.5842 90)
			(unlocked yes)
			(layer "F.SilkS")
			(effects
				(font
					(size 0.7874 0.5842)
					(thickness 0.1524)
				)
				(justify left)
			)
		)
		(property "Value" ""
			(at 0 0 0)
			(layer "F.Fab")
			(effects
				(font
					(size 1.27 1.27)
				)
			)
		)
		(duplicate_pad_numbers_are_jumpers no)
		(fp_poly
			(pts
				(xy 0.3048 -0.1016) (xy 0.3048 0.9906) (xy -0.3048 0.9906) (xy -0.3048 -0.1016)
			)
			(stroke
				(width 0)
				(type default)
			)
			(fill no)
			(layer "F.CrtYd")
		)
		(fp_line
			(start -0.3048 -0.1016)
			(end -0.3048 0.9906)
			(stroke
				(width 0.1)
				(type default)
			)
			(layer "F.Fab")
		)
		(fp_line
			(start -0.3048 0.9906)
			(end 0.3048 0.9906)
			(stroke
				(width 0.1)
				(type default)
			)
			(layer "F.Fab")
		)
		(fp_line
			(start 0.3048 -0.1016)
			(end -0.3048 -0.1016)
			(stroke
				(width 0.1)
				(type default)
			)
			(layer "F.Fab")
		)
		(fp_line
			(start 0.3048 0.9906)
			(end 0.3048 -0.1016)
			(stroke
				(width 0.1)
				(type default)
			)
			(layer "F.Fab")
		)
		(pad "1" smd rect
			(at 0 0)
			(size 0.508 0.508)
			(layers "F.Cu" "F.Mask" "F.Paste")
			(net "VR_PVCCIN_CPU1_AIREF4")
		)
		(pad "2" smd rect
			(at 0 0.889)
			(size 0.508 0.508)
			(layers "F.Cu" "F.Mask" "F.Paste")
			(net "GND")
		)
		(zone
			(layer "F.Cu")
			(hatch none 0.5)
			(connect_pads
				(clearance 0)
			)
			(min_thickness 0.25)
			(keepout
				(tracks allowed)
				(vias not_allowed)
				(pads allowed)
				(copperpour not_allowed)
				(footprints allowed)
			)
			(placement
				(enabled no)
				(sheetname "")
			)
			(fill
				(thermal_gap 0.5)
				(thermal_bridge_width 0.5)
				(island_removal_mode 0)
			)
			(polygon
				(pts
					(xy 29.759656 -78.08341) (xy 30.267656 -78.08341) (xy 30.267656 -77.70241) (xy 29.759656 -77.70241)
				)
			)
		)
		(zone
			(layer "F.Cu")
			(hatch none 0.5)
			(connect_pads
				(clearance 0)
			)
			(min_thickness 0.25)
			(keepout
				(tracks not_allowed)
				(vias allowed)
				(pads allowed)
				(copperpour not_allowed)
				(footprints allowed)
			)
			(placement
				(enabled no)
				(sheetname "")
			)
			(fill
				(thermal_gap 0.5)
				(thermal_bridge_width 0.5)
				(island_removal_mode 0)
			)
			(polygon
				(pts
					(xy 29.759656 -77.70241) (xy 30.267656 -77.70241) (xy 30.267656 -78.08341) (xy 29.759656 -78.08341)
				)
			)
		)
	)
	(footprint ""
		(layer "F.Cu")
		(at 395.6812 1.5748 -90)
		(property "Reference" "R8G21"
			(at 0 0 270)
			(layer "F.SilkS")
			(hide yes)
			(effects
				(font
					(size 1.27 1.27)
				)
			)
		)
		(property "Value" ""
			(at 0 0 270)
			(layer "F.Fab")
			(effects
				(font
					(size 1.27 1.27)
				)
			)
		)
		(duplicate_pad_numbers_are_jumpers no)
		(fp_poly
			(pts
				(xy -0.2794 -0.1016) (xy 0.2794 -0.1016) (xy 0.2794 0.9906) (xy -0.2794 0.9906)
			)
			(stroke
				(width 0)
				(type default)
			)
			(fill no)
			(layer "F.CrtYd")
		)
		(fp_line
			(start -0.2794 0.9906)
			(end 0.2794 0.9906)
			(stroke
				(width 0.1)
				(type default)
			)
			(layer "F.Fab")
		)
		(fp_line
			(start 0.2794 0.9906)
			(end 0.2794 -0.1016)
			(stroke
				(width 0.1)
				(type default)
			)
			(layer "F.Fab")
		)
		(fp_line
			(start -0.2794 -0.1016)
			(end -0.2794 0.9906)
			(stroke
				(width 0.1)
				(type default)
			)
			(layer "F.Fab")
		)
		(fp_line
			(start 0.2794 -0.1016)
			(end -0.2794 -0.1016)
			(stroke
				(width 0.1)
				(type default)
			)
			(layer "F.Fab")
		)
		(pad "1" smd rect
			(at 0 0 270)
			(size 0.508 0.508)
			(layers "F.Cu" "F.Mask" "F.Paste")
			(net "JTAG_TMS")
		)
		(pad "2" smd rect
			(at 0 0.889 270)
			(size 0.508 0.508)
			(layers "F.Cu" "F.Mask" "F.Paste")
			(net "JTAG_TMS_R")
		)
		(zone
			(layer "F.Cu")
			(hatch none 0.5)
			(connect_pads
				(clearance 0)
			)
			(min_thickness 0.25)
			(keepout
				(tracks not_allowed)
				(vias allowed)
				(pads allowed)
				(copperpour not_allowed)
				(footprints allowed)
			)
			(placement
				(enabled no)
				(sheetname "")
			)
			(fill
				(thermal_gap 0.5)
				(thermal_bridge_width 0.5)
				(island_removal_mode 0)
			)
			(polygon
				(pts
					(xy 395.0462 1.3208) (xy 395.0462 1.8288) (xy 395.4272 1.8288) (xy 395.4272 1.3208)
				)
			)
		)
		(zone
			(layer "F.Cu")
			(hatch none 0.5)
			(connect_pads
				(clearance 0)
			)
			(min_thickness 0.25)
			(keepout
				(tracks allowed)
				(vias not_allowed)
				(pads allowed)
				(copperpour not_allowed)
				(footprints allowed)
			)
			(placement
				(enabled no)
				(sheetname "")
			)
			(fill
				(thermal_gap 0.5)
				(thermal_bridge_width 0.5)
				(island_removal_mode 0)
			)
			(polygon
				(pts
					(xy 395.4272 1.3208) (xy 395.4272 1.8288) (xy 395.0462 1.8288) (xy 395.0462 1.3208)
				)
			)
		)
	)
	(footprint ""
		(layer "F.Cu")
		(at 472.7575 -139.573 90)
		(property "Reference" "R9A18"
			(at 0 0 90)
			(layer "F.SilkS")
			(hide yes)
			(effects
				(font
					(size 1.27 1.27)
				)
			)
		)
		(property "Value" ""
			(at 0 0 90)
			(layer "F.Fab")
			(effects
				(font
					(size 1.27 1.27)
				)
			)
		)
		(duplicate_pad_numbers_are_jumpers no)
		(fp_poly
			(pts
				(xy -0.2794 -0.1016) (xy 0.2794 -0.1016) (xy 0.2794 0.9906) (xy -0.2794 0.9906)
			)
			(stroke
				(width 0)
				(type default)
			)
			(fill no)
			(layer "F.CrtYd")
		)
		(fp_line
			(start 0.2794 -0.1016)
			(end -0.2794 -0.1016)
			(stroke
				(width 0.1)
				(type default)
			)
			(layer "F.Fab")
		)
		(fp_line
			(start -0.2794 -0.1016)
			(end -0.2794 0.9906)
			(stroke
				(width 0.1)
				(type default)
			)
			(layer "F.Fab")
		)
		(fp_line
			(start 0.2794 0.9906)
			(end 0.2794 -0.1016)
			(stroke
				(width 0.1)
				(type default)
			)
			(layer "F.Fab")
		)
		(fp_line
			(start -0.2794 0.9906)
			(end 0.2794 0.9906)
			(stroke
				(width 0.1)
				(type default)
			)
			(layer "F.Fab")
		)
		(pad "1" smd rect
			(at 0 0 90)
			(size 0.508 0.508)
			(layers "F.Cu" "F.Mask" "F.Paste")
			(net "P3V3_STBY")
		)
		(pad "2" smd rect
			(at 0 0.889 90)
			(size 0.508 0.508)
			(layers "F.Cu" "F.Mask" "F.Paste")
			(net "FM_PWR_LED")
		)
		(zone
			(layer "F.Cu")
			(hatch none 0.5)
			(connect_pads
				(clearance 0)
			)
			(min_thickness 0.25)
			(keepout
				(tracks allowed)
				(vias not_allowed)
				(pads allowed)
				(copperpour not_allowed)
				(footprints allowed)
			)
			(placement
				(enabled no)
				(sheetname "")
			)
			(fill
				(thermal_gap 0.5)
				(thermal_bridge_width 0.5)
				(island_removal_mode 0)
			)
			(polygon
				(pts
					(xy 473.0115 -139.319) (xy 473.0115 -139.827) (xy 473.3925 -139.827) (xy 473.3925 -139.319)
				)
			)
		)
		(zone
			(layer "F.Cu")
			(hatch none 0.5)
			(connect_pads
				(clearance 0)
			)
			(min_thickness 0.25)
			(keepout
				(tracks not_allowed)
				(vias allowed)
				(pads allowed)
				(copperpour not_allowed)
				(footprints allowed)
			)
			(placement
				(enabled no)
				(sheetname "")
			)
			(fill
				(thermal_gap 0.5)
				(thermal_bridge_width 0.5)
				(island_removal_mode 0)
			)
			(polygon
				(pts
					(xy 473.3925 -139.319) (xy 473.3925 -139.827) (xy 473.0115 -139.827) (xy 473.0115 -139.319)
				)
			)
		)
	)
)
